# SCM (Grand Teton) — schematic netlist excerpt (pin names and nets, part order shuffled) for the footprints in the layout excerpt that follows; sources: Cadence DE-HDL packaged netlist, KiCad conversion of 12092022_DA0F0TMDCD0_F0T_Management_Board_D_brd_V3_OCP.brd

C302  Q_CAP  0.1UF 25V 10% X7R  pkg 0402  page 56 : A = P3V3_LDO ; B = GND
R543  Q_RES  4.7K 1% EMPTY  pkg 0402LF  page 21 : A = P3V3_AUX ; B = SPI_BMC_HOLD1_N

(kicad_pcb
	(version 20260206)
	(generator "pcbnew")
	(generator_version "10.0")
	(general
		(thickness 1.6)
		(legacy_teardrops no)
	)
	(paper "A4")
	(title_block
		(title "12092022_DA0F0TMDCD0_F0T_Management_Board_D_brd_V3_OCP.brd")
		(comment 1 "Grand Teton / footprints 527-528 of 1440")
	)
	(layers
		(0 "F.Cu" signal "TOP")
		(4 "In1.Cu" signal "GND")
		(6 "In2.Cu" signal "IN1")
		(8 "In3.Cu" signal "GND1")
		(10 "In4.Cu" signal "IN2")
		(12 "In5.Cu" signal "VCC")
		(14 "In6.Cu" signal "VCC1")
		(16 "In7.Cu" signal "IN3")
		(18 "In8.Cu" signal "GND2")
		(20 "In9.Cu" signal "IN4")
		(22 "In10.Cu" signal "GND3")
		(2 "B.Cu" signal "BOTTOM")
		(9 "F.Adhes" user "F.Adhesive")
		(11 "B.Adhes" user "B.Adhesive")
		(13 "F.Paste" user "Package Geometry/Pastemask Top")
		(15 "B.Paste" user "Package Geometry/Pastemask Bottom")
		(5 "F.SilkS" user "Ref Des/Silkscreen Top")
		(7 "B.SilkS" user "Ref Des/Silkscreen Bottom")
		(1 "F.Mask" user "Board Geometry/Soldermask Top")
		(3 "B.Mask" user "Board Geometry/Soldermask Bottom")
		(17 "Dwgs.User" user "User.Drawings")
		(19 "Cmts.User" user "User.Comments")
		(21 "Eco1.User" user "User.Eco1")
		(23 "Eco2.User" user "User.Eco2")
		(25 "Edge.Cuts" user "Board Geometry/Outline")
		(27 "Margin" user)
		(31 "F.CrtYd" user "Package Geometry/Place Bound Top")
		(29 "B.CrtYd" user "Package Geometry/Place Bound Bottom")
		(35 "F.Fab" user "Ref Des/Assembly Top")
		(33 "B.Fab" user "Ref Des/Assembly Bottom")
	)
	(footprint ""
		(layer "F.Cu")
		(at 16.256 -33.4518 -90)
		(property "Reference" "C302"
			(at 0 0 270)
			(layer "F.SilkS")
			(hide yes)
			(effects
				(font
					(size 1.27 1.27)
				)
			)
		)
		(property "Value" ""
			(at 0 0 270)
			(layer "F.Fab")
			(effects
				(font
					(size 1.27 1.27)
				)
			)
		)
		(duplicate_pad_numbers_are_jumpers no)
		(fp_line
			(start -0.7874 0.4064)
			(end -0.7874 -0.4064)
			(stroke
				(width 0.1524)
				(type default)
			)
			(layer "F.SilkS")
		)
		(fp_line
			(start 0.7874 0.4064)
			(end -0.7874 0.4064)
			(stroke
				(width 0.1524)
				(type default)
			)
			(layer "F.SilkS")
		)
		(fp_line
			(start -0.7874 -0.4064)
			(end 0.7874 -0.4064)
			(stroke
				(width 0.1524)
				(type default)
			)
			(layer "F.SilkS")
		)
		(fp_line
			(start 0.7874 -0.4064)
			(end 0.7874 0.4064)
			(stroke
				(width 0.1524)
				(type default)
			)
			(layer "F.SilkS")
		)
		(fp_line
			(start -0.67945 0.3048)
			(end -0.67945 -0.305054)
			(stroke
				(width 0.1)
				(type default)
			)
			(layer "F.Fab")
		)
		(fp_line
			(start -0.12065 0.3048)
			(end -0.67945 0.3048)
			(stroke
				(width 0.1)
				(type default)
			)
			(layer "F.Fab")
		)
		(fp_line
			(start 0.120396 0.3048)
			(end 0.120396 0.2794)
			(stroke
				(width 0.1)
				(type default)
			)
			(layer "F.Fab")
		)
		(fp_line
			(start 0.67945 0.3048)
			(end 0.120396 0.3048)
			(stroke
				(width 0.1)
				(type default)
			)
			(layer "F.Fab")
		)
		(fp_line
			(start -0.12065 0.2794)
			(end -0.12065 0.3048)
			(stroke
				(width 0.1)
				(type default)
			)
			(layer "F.Fab")
		)
		(fp_line
			(start 0.120396 0.2794)
			(end -0.12065 0.2794)
			(stroke
				(width 0.1)
				(type default)
			)
			(layer "F.Fab")
		)
		(fp_line
			(start -0.12065 -0.2794)
			(end 0.12065 -0.2794)
			(stroke
				(width 0.1)
				(type default)
			)
			(layer "F.Fab")
		)
		(fp_line
			(start 0.12065 -0.2794)
			(end 0.12065 -0.3048)
			(stroke
				(width 0.1)
				(type default)
			)
			(layer "F.Fab")
		)
		(fp_line
			(start 0.12065 -0.3048)
			(end 0.67945 -0.3048)
			(stroke
				(width 0.1)
				(type default)
			)
			(layer "F.Fab")
		)
		(fp_line
			(start 0.67945 -0.3048)
			(end 0.67945 0.3048)
			(stroke
				(width 0.1)
				(type default)
			)
			(layer "F.Fab")
		)
		(fp_line
			(start -0.67945 -0.305054)
			(end -0.12065 -0.305054)
			(stroke
				(width 0.1)
				(type default)
			)
			(layer "F.Fab")
		)
		(fp_line
			(start -0.12065 -0.305054)
			(end -0.12065 -0.2794)
			(stroke
				(width 0.1)
				(type default)
			)
			(layer "F.Fab")
		)
		(pad "1" smd circle
			(at -0.40005 0 270)
			(size 0 0)
			(layers "F.Cu" "F.Mask" "F.Paste")
			(net "P3V3_LDO")
		)
		(pad "2" smd circle
			(at 0.40005 0 270)
			(size 0 0)
			(layers "F.Cu" "F.Mask" "F.Paste")
			(net "GND")
		)
	)
	(footprint ""
		(layer "F.Cu")
		(at 25.273 -68.834 90)
		(property "Reference" "R543"
			(at 0 0 90)
			(layer "F.SilkS")
			(hide yes)
			(effects
				(font
					(size 1.27 1.27)
				)
			)
		)
		(property "Value" ""
			(at 0 0 90)
			(layer "F.Fab")
			(effects
				(font
					(size 1.27 1.27)
				)
			)
		)
		(duplicate_pad_numbers_are_jumpers no)
		(fp_line
			(start 0.7874 -0.4064)
			(end 0.7874 0.4064)
			(stroke
				(width 0.1524)
				(type default)
			)
			(layer "F.SilkS")
		)
		(fp_line
			(start -0.7874 -0.4064)
			(end 0.7874 -0.4064)
			(stroke
				(width 0.1524)
				(type default)
			)
			(layer "F.SilkS")
		)
		(fp_line
			(start 0.7874 0.4064)
			(end -0.7874 0.4064)
			(stroke
				(width 0.1524)
				(type default)
			)
			(layer "F.SilkS")
		)
		(fp_line
			(start -0.7874 0.4064)
			(end -0.7874 -0.4064)
			(stroke
				(width 0.1524)
				(type default)
			)
			(layer "F.SilkS")
		)
		(fp_line
			(start -0.12065 -0.305054)
			(end -0.12065 -0.2794)
			(stroke
				(width 0.1)
				(type default)
			)
			(layer "F.Fab")
		)
		(fp_line
			(start -0.67945 -0.305054)
			(end -0.12065 -0.305054)
			(stroke
				(width 0.1)
				(type default)
			)
			(layer "F.Fab")
		)
		(fp_line
			(start 0.67945 -0.3048)
			(end 0.67945 0.3048)
			(stroke
				(width 0.1)
				(type default)
			)
			(layer "F.Fab")
		)
		(fp_line
			(start 0.12065 -0.3048)
			(end 0.67945 -0.3048)
			(stroke
				(width 0.1)
				(type default)
			)
			(layer "F.Fab")
		)
		(fp_line
			(start 0.12065 -0.2794)
			(end 0.12065 -0.3048)
			(stroke
				(width 0.1)
				(type default)
			)
			(layer "F.Fab")
		)
		(fp_line
			(start -0.12065 -0.2794)
			(end 0.12065 -0.2794)
			(stroke
				(width 0.1)
				(type default)
			)
			(layer "F.Fab")
		)
		(fp_line
			(start 0.120396 0.2794)
			(end -0.12065 0.2794)
			(stroke
				(width 0.1)
				(type default)
			)
			(layer "F.Fab")
		)
		(fp_line
			(start -0.12065 0.2794)
			(end -0.12065 0.3048)
			(stroke
				(width 0.1)
				(type default)
			)
			(layer "F.Fab")
		)
		(fp_line
			(start 0.67945 0.3048)
			(end 0.120396 0.3048)
			(stroke
				(width 0.1)
				(type default)
			)
			(layer "F.Fab")
		)
		(fp_line
			(start 0.120396 0.3048)
			(end 0.120396 0.2794)
			(stroke
				(width 0.1)
				(type default)
			)
			(layer "F.Fab")
		)
		(fp_line
			(start -0.12065 0.3048)
			(end -0.67945 0.3048)
			(stroke
				(width 0.1)
				(type default)
			)
			(layer "F.Fab")
		)
		(fp_line
			(start -0.67945 0.3048)
			(end -0.67945 -0.305054)
			(stroke
				(width 0.1)
				(type default)
			)
			(layer "F.Fab")
		)
		(pad "1" smd circle
			(at -0.40005 0 90)
			(size 0 0)
			(layers "F.Cu" "F.Mask" "F.Paste")
			(net "P3V3_AUX")
		)
		(pad "2" smd circle
			(at 0.40005 0 90)
			(size 0 0)
			(layers "F.Cu" "F.Mask" "F.Paste")
			(net "SPI_BMC_HOLD1_N")
		)
	)
)
